# T6G (Grand Teton) — schematic netlist excerpt (pin names and nets, part order shuffled) for the footprints in the layout excerpt that follows; sources: Cadence DE-HDL packaged netlist, KiCad conversion of 04192023_DAF0TMB3IC0_F0TG_MB_C_brd_V02_OCP.brd

C826  Q_CAP_DIFFBUS  DIFF BUS_0.22UF 6.3V 20% X6S  pkg C0201  page 65 : \1\ = P5E_CPU1_P0_TX_C_DN<5> ; \2\ = P5E_CPU1_P0_TX_DN<5>

PL60  Q_INDUCTOR4P_14  150NH IND  pkg L_TLM117513Q-151QL_11X7-5XA  page 195
  \1\  = SW_PVDDCR_CPU0_P0_SW4
  \2\  = IND_CPU0_P0_CPL3
  \3\  = GND
  \4\  = PVDDCR_CPU0_P0

R6863  Q_RES  33 5% CHIP  pkg 0402LF  page 151 : A = SMB_HOST_CLK_3V3AUX_SDA_R1 ; B = SMB_9ZXL045_P1_SDA

(kicad_pcb
	(version 20260206)
	(generator "pcbnew")
	(generator_version "10.0")
	(general
		(thickness 1.6)
		(legacy_teardrops no)
	)
	(paper "A4")
	(title_block
		(title "04192023_DAF0TMB3IC0_F0TG_MB_C_brd_V02_OCP.brd")
		(comment 1 "Grand Teton / footprints 480-482 of 8354")
	)
	(layers
		(0 "F.Cu" signal "TOP")
		(4 "In1.Cu" signal "GND")
		(6 "In2.Cu" signal "IN1")
		(8 "In3.Cu" signal "GND1")
		(10 "In4.Cu" signal "IN2")
		(12 "In5.Cu" signal "GND2")
		(14 "In6.Cu" signal "IN3")
		(16 "In7.Cu" signal "GND3")
		(18 "In8.Cu" signal "VCC")
		(20 "In9.Cu" signal "VCC1")
		(22 "In10.Cu" signal "GND4")
		(24 "In11.Cu" signal "IN4")
		(26 "In12.Cu" signal "GND5")
		(28 "In13.Cu" signal "IN5")
		(30 "In14.Cu" signal "GND6")
		(32 "In15.Cu" signal "IN6")
		(34 "In16.Cu" signal "GND7")
		(2 "B.Cu" signal "BOTTOM")
		(9 "F.Adhes" user "F.Adhesive")
		(11 "B.Adhes" user "B.Adhesive")
		(13 "F.Paste" user "Package Geometry/Pastemask Top")
		(15 "B.Paste" user "Package Geometry/Pastemask Bottom")
		(5 "F.SilkS" user "Ref Des/Silkscreen Top")
		(7 "B.SilkS" user "Ref Des/Silkscreen Bottom")
		(1 "F.Mask" user "Board Geometry/Soldermask Top")
		(3 "B.Mask" user "Board Geometry/Soldermask Bottom")
		(17 "Dwgs.User" user "User.Drawings")
		(19 "Cmts.User" user "User.Comments")
		(21 "Eco1.User" user "User.Eco1")
		(23 "Eco2.User" user "User.Eco2")
		(25 "Edge.Cuts" user "Board Geometry/Outline")
		(27 "Margin" user)
		(31 "F.CrtYd" user "Package Geometry/Place Bound Top")
		(29 "B.CrtYd" user "Package Geometry/Place Bound Bottom")
		(35 "F.Fab" user "Ref Des/Assembly Top")
		(33 "B.Fab" user "Ref Des/Assembly Bottom")
	)
	(footprint ""
		(layer "F.Cu")
		(at 389.291322 -192.061084 180)
		(property "Reference" "PL60"
			(at -5.632196 3.113278 90)
			(unlocked yes)
			(layer "F.SilkS")
			(effects
				(font
					(size 0.7874 0.5842)
					(thickness 0.1524)
				)
				(justify left)
			)
		)
		(property "Value" ""
			(at 0 0 180)
			(layer "F.Fab")
			(effects
				(font
					(size 1.27 1.27)
				)
			)
		)
		(duplicate_pad_numbers_are_jumpers no)
		(fp_line
			(start 3.750056 5.500116)
			(end 3.750056 -5.500116)
			(stroke
				(width 0.1524)
				(type default)
			)
			(layer "F.SilkS")
		)
		(fp_line
			(start 3.750056 -5.500116)
			(end 2.393442 -5.500116)
			(stroke
				(width 0.1524)
				(type default)
			)
			(layer "F.SilkS")
		)
		(fp_line
			(start 2.393442 5.500116)
			(end 3.750056 5.500116)
			(stroke
				(width 0.1524)
				(type default)
			)
			(layer "F.SilkS")
		)
		(fp_line
			(start -2.393442 5.500116)
			(end -3.750056 5.500116)
			(stroke
				(width 0.1524)
				(type default)
			)
			(layer "F.SilkS")
		)
		(fp_line
			(start -3.750056 5.500116)
			(end -3.750056 -5.500116)
			(stroke
				(width 0.1524)
				(type default)
			)
			(layer "F.SilkS")
		)
		(fp_line
			(start -3.750056 -5.500116)
			(end -2.393442 -5.500116)
			(stroke
				(width 0.1524)
				(type default)
			)
			(layer "F.SilkS")
		)
		(fp_poly
			(pts
				(xy -3.9116 -4.249928) (xy -4.662678 -3.874516) (xy -4.662678 -4.62534)
			)
			(stroke
				(width 0)
				(type default)
			)
			(fill yes)
			(layer "F.SilkS")
		)
		(fp_line
			(start 3.750056 5.500116)
			(end 3.750056 -5.500116)
			(stroke
				(width 0.1)
				(type default)
			)
			(layer "F.Fab")
		)
		(fp_line
			(start 3.750056 -5.500116)
			(end -3.750056 -5.500116)
			(stroke
				(width 0.1)
				(type default)
			)
			(layer "F.Fab")
		)
		(fp_line
			(start -3.750056 5.500116)
			(end 3.750056 5.500116)
			(stroke
				(width 0.1)
				(type default)
			)
			(layer "F.Fab")
		)
		(fp_line
			(start -3.750056 -5.500116)
			(end -3.750056 5.500116)
			(stroke
				(width 0.1)
				(type default)
			)
			(layer "F.Fab")
		)
		(fp_poly
			(pts
				(xy -4.9276 -4.757928) (xy -4.9276 -3.741928) (xy -3.9116 -4.249928)
			)
			(stroke
				(width 0)
				(type default)
			)
			(fill yes)
			(layer "F.Fab")
		)
		(pad "1" smd rect
			(at 0 -4.249928 90)
			(size 2.413 4.5212)
			(layers "F.Cu" "F.Mask" "F.Paste")
			(net "SW_PVDDCR_CPU0_P0_SW4")
		)
		(pad "2" smd rect
			(at 0 -1.175004 90)
			(size 1.3716 4.5212)
			(layers "F.Cu" "F.Mask" "F.Paste")
			(net "IND_CPU0_P0_CPL3")
		)
		(pad "3" smd rect
			(at 0 1.175004 90)
			(size 1.3716 4.5212)
			(layers "F.Cu" "F.Mask" "F.Paste")
			(net "GND")
		)
		(pad "4" smd rect
			(at 0 4.249928 90)
			(size 2.413 4.5212)
			(layers "F.Cu" "F.Mask" "F.Paste")
			(net "PVDDCR_CPU0_P0")
		)
	)
	(footprint ""
		(layer "F.Cu")
		(at 50.711354 -373.03583 -90)
		(property "Reference" "C826"
			(at 0 0 270)
			(layer "F.SilkS")
			(hide yes)
			(effects
				(font
					(size 1.27 1.27)
				)
			)
		)
		(property "Value" ""
			(at 0 0 270)
			(layer "F.Fab")
			(effects
				(font
					(size 1.27 1.27)
				)
			)
		)
		(duplicate_pad_numbers_are_jumpers no)
		(fp_line
			(start -0.299974 0.150114)
			(end -0.299974 -0.150114)
			(stroke
				(width 0.1)
				(type default)
			)
			(layer "F.Fab")
		)
		(fp_line
			(start 0.299974 0.150114)
			(end -0.299974 0.150114)
			(stroke
				(width 0.1)
				(type default)
			)
			(layer "F.Fab")
		)
		(fp_line
			(start -0.299974 -0.150114)
			(end 0.299974 -0.150114)
			(stroke
				(width 0.1)
				(type default)
			)
			(layer "F.Fab")
		)
		(fp_line
			(start 0.299974 -0.150114)
			(end 0.299974 0.150114)
			(stroke
				(width 0.1)
				(type default)
			)
			(layer "F.Fab")
		)
		(pad "1" smd rect
			(at -0.2667 0 270)
			(size 0.3048 0.381)
			(layers "F.Cu" "F.Mask" "F.Paste")
			(net "P5E_CPU1_P0_TX_C_DN<5>")
		)
		(pad "2" smd rect
			(at 0.2667 0 270)
			(size 0.3048 0.381)
			(layers "F.Cu" "F.Mask" "F.Paste")
			(net "P5E_CPU1_P0_TX_DN<5>")
		)
	)
	(footprint ""
		(layer "F.Cu")
		(at 103.125524 -414.329626)
		(property "Reference" "R6863"
			(at 0 0 0)
			(layer "F.SilkS")
			(hide yes)
			(effects
				(font
					(size 1.27 1.27)
				)
			)
		)
		(property "Value" ""
			(at 0 0 0)
			(layer "F.Fab")
			(effects
				(font
					(size 1.27 1.27)
				)
			)
		)
		(duplicate_pad_numbers_are_jumpers no)
		(fp_line
			(start -0.7874 -0.4064)
			(end 0.7874 -0.4064)
			(stroke
				(width 0.1524)
				(type default)
			)
			(layer "F.SilkS")
		)
		(fp_line
			(start -0.7874 0.4064)
			(end -0.7874 -0.4064)
			(stroke
				(width 0.1524)
				(type default)
			)
			(layer "F.SilkS")
		)
		(fp_line
			(start 0.7874 -0.4064)
			(end 0.7874 0.4064)
			(stroke
				(width 0.1524)
				(type default)
			)
			(layer "F.SilkS")
		)
		(fp_line
			(start 0.7874 0.4064)
			(end -0.7874 0.4064)
			(stroke
				(width 0.1524)
				(type default)
			)
			(layer "F.SilkS")
		)
		(fp_line
			(start -0.67945 -0.305054)
			(end -0.12065 -0.305054)
			(stroke
				(width 0.1)
				(type default)
			)
			(layer "F.Fab")
		)
		(fp_line
			(start -0.67945 0.3048)
			(end -0.67945 -0.305054)
			(stroke
				(width 0.1)
				(type default)
			)
			(layer "F.Fab")
		)
		(fp_line
			(start -0.12065 -0.305054)
			(end -0.12065 -0.2794)
			(stroke
				(width 0.1)
				(type default)
			)
			(layer "F.Fab")
		)
		(fp_line
			(start -0.12065 -0.2794)
			(end 0.12065 -0.2794)
			(stroke
				(width 0.1)
				(type default)
			)
			(layer "F.Fab")
		)
		(fp_line
			(start -0.12065 0.2794)
			(end -0.12065 0.3048)
			(stroke
				(width 0.1)
				(type default)
			)
			(layer "F.Fab")
		)
		(fp_line
			(start -0.12065 0.3048)
			(end -0.67945 0.3048)
			(stroke
				(width 0.1)
				(type default)
			)
			(layer "F.Fab")
		)
		(fp_line
			(start 0.120396 0.2794)
			(end -0.12065 0.2794)
			(stroke
				(width 0.1)
				(type default)
			)
			(layer "F.Fab")
		)
		(fp_line
			(start 0.120396 0.3048)
			(end 0.120396 0.2794)
			(stroke
				(width 0.1)
				(type default)
			)
			(layer "F.Fab")
		)
		(fp_line
			(start 0.12065 -0.3048)
			(end 0.67945 -0.3048)
			(stroke
				(width 0.1)
				(type default)
			)
			(layer "F.Fab")
		)
		(fp_line
			(start 0.12065 -0.2794)
			(end 0.12065 -0.3048)
			(stroke
				(width 0.1)
				(type default)
			)
			(layer "F.Fab")
		)
		(fp_line
			(start 0.67945 -0.3048)
			(end 0.67945 0.3048)
			(stroke
				(width 0.1)
				(type default)
			)
			(layer "F.Fab")
		)
		(fp_line
			(start 0.67945 0.3048)
			(end 0.120396 0.3048)
			(stroke
				(width 0.1)
				(type default)
			)
			(layer "F.Fab")
		)
		(pad "1" smd circle
			(at -0.40005 0)
			(size 0 0)
			(layers "F.Cu" "F.Mask" "F.Paste")
			(net "SMB_HOST_CLK_3V3AUX_SDA_R1")
		)
		(pad "2" smd circle
			(at 0.40005 0)
			(size 0 0)
			(layers "F.Cu" "F.Mask" "F.Paste")
			(net "SMB_9ZXL045_P1_SDA")
		)
	)
)
